(kicad_pcb
	(version 20221018)
	(generator pcbnew)
	(general
    (thickness 1.62)
  )
	(paper "A4")
	(title_block
    (title "ECP5 - Datacenter Secure Control Module (DC-SCM)")
    (date "2024-07-01")
    (rev "1.2.1")
		(comment 9 "footprints 56-63 of 506")
	)
	(layers
    (0 "F.Cu" signal)
    (1 "In1.Cu" power)
    (2 "In2.Cu" signal)
    (3 "In3.Cu" power)
    (4 "In4.Cu" power)
    (5 "In5.Cu" signal)
    (6 "In6.Cu" power)
    (31 "B.Cu" signal)
    (32 "B.Adhes" user "B.Adhesive")
    (33 "F.Adhes" user "F.Adhesive")
    (34 "B.Paste" user)
    (35 "F.Paste" user)
    (36 "B.SilkS" user "B.Silkscreen")
    (37 "F.SilkS" user "F.Silkscreen")
    (38 "B.Mask" user)
    (39 "F.Mask" user)
    (40 "Dwgs.User" user "User.Drawings")
    (41 "Cmts.User" user "User.Comments")
    (42 "Eco1.User" user "User.Eco1")
    (43 "Eco2.User" user "User.Eco2")
    (44 "Edge.Cuts" user)
    (45 "Margin" user)
    (46 "B.CrtYd" user "B.Courtyard")
    (47 "F.CrtYd" user "F.Courtyard")
    (48 "B.Fab" user)
    (49 "F.Fab" user)
  )
	(footprint "antmicro-footprints:C_0402_1005Metric" (layer "F.Cu")
    (at 111.25 97.63 90)
    (descr "Capacitor SMD 0402")
    (tags "capacitor SMD 0402")
    (property "Author" "Antmicro")
    (property "Dielectric" "X7R")
    (property "License" "Apache-2.0")
    (property "MPN" "GRM155R71H103KA88D")
    (property "Manufacturer" "Murata")
    (property "Public" "False")
    (property "Sheetfile" "ethernet.kicad_sch")
    (property "Sheetname" "Ethernet")
    (property "Val" "10n")
    (property "Voltage" "50V")
    (property "ki_description" "SMD Multilayer Ceramic Capacitor, 10000 pF, 50 V, 0402 [1005 Metric], ± 10%, X7R, GRM Series")
    (property "ki_keywords" "0402, SMT, CAPACITOR, PASSIVE")
    (attr smd)
    (fp_text reference "C20" (at 0.02 0.995 90) (layer "F.SilkS")
        (effects (font (size 0.7 0.7) (thickness 0.127)))
    )
    (fp_text value "C_10n_0402" (at 0 1.17 90) (layer "F.Fab")
        (effects (font (size 1 1) (thickness 0.15)))
    )
    (fp_text user "Author: Antmicro" (at -0.939 3.399 90) (layer "F.Fab") hide
        (effects (font (size 0.7 0.7) (thickness 0.15)) (justify left bottom))
    )
    (fp_text user "${REFERENCE}" (at 0 0 90) (layer "F.Fab")
        (effects (font (size 0.25 0.25) (thickness 0.04)))
    )
    (fp_text user "License: Apache-2.0" (at -0.939 5.799 90) (layer "F.Fab") hide
        (effects (font (size 0.7 0.7) (thickness 0.15)) (justify left bottom))
    )
    (fp_rect (start -0.925 -0.47) (end 0.925 0.47)
      (stroke (width 0.05) (type default)) (fill none) (layer "F.CrtYd"))
    (fp_line (start -0.494 -0.25) (end 0.504 -0.25)
      (stroke (width 0.15) (type solid)) (layer "F.Fab"))
    (fp_line (start -0.494 0.248) (end -0.494 -0.25)
      (stroke (width 0.15) (type solid)) (layer "F.Fab"))
    (fp_line (start 0.504 -0.25) (end 0.504 0.248)
      (stroke (width 0.15) (type solid)) (layer "F.Fab"))
    (fp_line (start 0.504 0.248) (end -0.494 0.248)
      (stroke (width 0.15) (type solid)) (layer "F.Fab"))
    (pad "1" smd roundrect (at -0.48 0 90) (size 0.59 0.64) (layers "F.Cu" "F.Paste" "F.Mask") (roundrect_rratio 0.25)
      (net 1 "GND") (pintype "passive"))
    (pad "2" smd roundrect (at 0.48 0 90) (size 0.59 0.64) (layers "F.Cu" "F.Paste" "F.Mask") (roundrect_rratio 0.25)
      (net 2 "VCC3V3") (pintype "passive"))
  )
	(footprint "antmicro-footprints:C_0402_1005Metric" (layer "F.Cu")
    (at 131 119.685)
    (descr "Capacitor SMD 0402")
    (tags "capacitor SMD 0402")
    (property "Author" "Antmicro")
    (property "Dielectric" "X7R")
    (property "License" "Apache-2.0")
    (property "MPN" "GRM155R71H103KA88D")
    (property "Manufacturer" "Murata")
    (property "Public" "False")
    (property "Sheetfile" "interfaces.kicad_sch")
    (property "Sheetname" "Interfaces")
    (property "Val" "10n")
    (property "Voltage" "50V")
    (property "ki_description" "SMD Multilayer Ceramic Capacitor, 10000 pF, 50 V, 0402 [1005 Metric], ± 10%, X7R, GRM Series")
    (property "ki_keywords" "0402, SMT, CAPACITOR, PASSIVE")
    (attr smd)
    (fp_text reference "C26" (at -0.035 1.025) (layer "F.SilkS")
        (effects (font (size 0.7 0.7) (thickness 0.127)))
    )
    (fp_text value "C_10n_0402" (at 0 1.17) (layer "F.Fab")
        (effects (font (size 1 1) (thickness 0.15)))
    )
    (fp_text user "License: Apache-2.0" (at -0.939 5.799) (layer "F.Fab") hide
        (effects (font (size 0.7 0.7) (thickness 0.15)) (justify left bottom))
    )
    (fp_text user "${REFERENCE}" (at 0 0) (layer "F.Fab")
        (effects (font (size 0.25 0.25) (thickness 0.04)))
    )
    (fp_text user "Author: Antmicro" (at -0.939 3.399) (layer "F.Fab") hide
        (effects (font (size 0.7 0.7) (thickness 0.15)) (justify left bottom))
    )
    (fp_rect (start -0.925 -0.47) (end 0.925 0.47)
      (stroke (width 0.05) (type default)) (fill none) (layer "F.CrtYd"))
    (fp_line (start -0.494 -0.25) (end 0.504 -0.25)
      (stroke (width 0.15) (type solid)) (layer "F.Fab"))
    (fp_line (start -0.494 0.248) (end -0.494 -0.25)
      (stroke (width 0.15) (type solid)) (layer "F.Fab"))
    (fp_line (start 0.504 -0.25) (end 0.504 0.248)
      (stroke (width 0.15) (type solid)) (layer "F.Fab"))
    (fp_line (start 0.504 0.248) (end -0.494 0.248)
      (stroke (width 0.15) (type solid)) (layer "F.Fab"))
    (pad "1" smd roundrect (at -0.48 0) (size 0.59 0.64) (layers "F.Cu" "F.Paste" "F.Mask") (roundrect_rratio 0.25)
      (net 1 "GND") (pintype "passive"))
    (pad "2" smd roundrect (at 0.48 0) (size 0.59 0.64) (layers "F.Cu" "F.Paste" "F.Mask") (roundrect_rratio 0.25)
      (net 2 "VCC3V3") (pintype "passive"))
  )
	(footprint "antmicro-footprints:R_0402_1005Metric" (layer "F.Cu")
    (at 101 104 -90)
    (descr "Resistor SMD 0402")
    (tags "resistor SMD 0402")
    (property "Author" "Antmicro")
    (property "License" "Apache-2.0")
    (property "MPN" "CR0402-FX-1022GLF")
    (property "Manufacturer" "Bourns")
    (property "Public" "False")
    (property "Sheetfile" "ethernet.kicad_sch")
    (property "Sheetname" "Ethernet")
    (property "Tolerance" "1%")
    (property "Val" "10k2")
    (property "ki_description" "SMD Chip Resistor")
    (property "ki_keywords" "0402, SMT, RESISTOR, PASSIVE")
    (attr smd)
    (fp_text reference "R4" (at 0.04 -8.96 90) (layer "F.SilkS")
        (effects (font (size 0.7 0.7) (thickness 0.127)))
    )
    (fp_text value "R_10k2_0402" (at 0 1.17 90) (layer "F.Fab")
        (effects (font (size 1 1) (thickness 0.15)))
    )
    (fp_text user "License: Apache-2.0" (at -0.95 5.169 -90) (layer "F.Fab") hide
        (effects (font (size 0.7 0.7) (thickness 0.15)) (justify left bottom))
    )
    (fp_text user "${REFERENCE}" (at 0 0 90) (layer "F.Fab")
        (effects (font (size 0.25 0.25) (thickness 0.04)))
    )
    (fp_text user "Author: Antmicro" (at -0.95 4.169 -90) (layer "F.Fab") hide
        (effects (font (size 0.7 0.7) (thickness 0.15)) (justify left bottom))
    )
    (fp_rect (start -0.925 -0.47) (end 0.925 0.47)
      (stroke (width 0.05) (type default)) (fill none) (layer "F.CrtYd"))
    (fp_rect (start -0.5 -0.25) (end 0.5 0.25)
      (stroke (width 0.15) (type solid)) (fill none) (layer "F.Fab"))
    (pad "1" smd roundrect (at -0.48 0 270) (size 0.59 0.64) (layers "F.Cu" "F.Paste" "F.Mask") (roundrect_rratio 0.25)
      (net 157 "RGMII_RXD3") (pintype "passive"))
    (pad "2" smd roundrect (at 0.48 0 270) (size 0.59 0.64) (layers "F.Cu" "F.Paste" "F.Mask") (roundrect_rratio 0.25)
      (net 2 "VCC3V3") (pintype "passive"))
  )
	(footprint "antmicro-footprints:R_0402_1005Metric" (layer "F.Cu")
    (at 102 104 -90)
    (descr "Resistor SMD 0402")
    (tags "resistor SMD 0402")
    (property "Author" "Antmicro")
    (property "License" "Apache-2.0")
    (property "MPN" "CR0402-FX-1022GLF")
    (property "Manufacturer" "Bourns")
    (property "Public" "False")
    (property "Sheetfile" "ethernet.kicad_sch")
    (property "Sheetname" "Ethernet")
    (property "Tolerance" "1%")
    (property "Val" "10k2")
    (property "ki_description" "SMD Chip Resistor")
    (property "ki_keywords" "0402, SMT, RESISTOR, PASSIVE")
    (attr smd)
    (fp_text reference "R3" (at 0.04 -8.955476 90) (layer "F.SilkS")
        (effects (font (size 0.7 0.7) (thickness 0.127)))
    )
    (fp_text value "R_10k2_0402" (at 0 1.17 90) (layer "F.Fab")
        (effects (font (size 1 1) (thickness 0.15)))
    )
    (fp_text user "License: Apache-2.0" (at -0.95 5.169 -90) (layer "F.Fab") hide
        (effects (font (size 0.7 0.7) (thickness 0.15)) (justify left bottom))
    )
    (fp_text user "${REFERENCE}" (at 0 0 90) (layer "F.Fab")
        (effects (font (size 0.25 0.25) (thickness 0.04)))
    )
    (fp_text user "Author: Antmicro" (at -0.95 4.169 -90) (layer "F.Fab") hide
        (effects (font (size 0.7 0.7) (thickness 0.15)) (justify left bottom))
    )
    (fp_rect (start -0.925 -0.47) (end 0.925 0.47)
      (stroke (width 0.05) (type default)) (fill none) (layer "F.CrtYd"))
    (fp_rect (start -0.5 -0.25) (end 0.5 0.25)
      (stroke (width 0.15) (type solid)) (fill none) (layer "F.Fab"))
    (pad "1" smd roundrect (at -0.48 0 270) (size 0.59 0.64) (layers "F.Cu" "F.Paste" "F.Mask") (roundrect_rratio 0.25)
      (net 156 "RGMII_RXD2") (pintype "passive"))
    (pad "2" smd roundrect (at 0.48 0 270) (size 0.59 0.64) (layers "F.Cu" "F.Paste" "F.Mask") (roundrect_rratio 0.25)
      (net 2 "VCC3V3") (pintype "passive"))
  )
	(footprint "antmicro-footprints:R_0402_1005Metric" (layer "F.Cu")
    (at 103 104 -90)
    (descr "Resistor SMD 0402")
    (tags "resistor SMD 0402")
    (property "Author" "Antmicro")
    (property "License" "Apache-2.0")
    (property "MPN" "CR0402-FX-1022GLF")
    (property "Manufacturer" "Bourns")
    (property "Public" "False")
    (property "Sheetfile" "ethernet.kicad_sch")
    (property "Sheetname" "Ethernet")
    (property "Tolerance" "1%")
    (property "Val" "10k2")
    (property "ki_description" "SMD Chip Resistor")
    (property "ki_keywords" "0402, SMT, RESISTOR, PASSIVE")
    (attr smd)
    (fp_text reference "R2" (at 0.04 -8.950952 90) (layer "F.SilkS")
        (effects (font (size 0.7 0.7) (thickness 0.127)))
    )
    (fp_text value "R_10k2_0402" (at 0 1.17 90) (layer "F.Fab")
        (effects (font (size 1 1) (thickness 0.15)))
    )
    (fp_text user "License: Apache-2.0" (at -0.95 5.169 -90) (layer "F.Fab") hide
        (effects (font (size 0.7 0.7) (thickness 0.15)) (justify left bottom))
    )
    (fp_text user "${REFERENCE}" (at 0 0 90) (layer "F.Fab")
        (effects (font (size 0.25 0.25) (thickness 0.04)))
    )
    (fp_text user "Author: Antmicro" (at -0.95 4.169 -90) (layer "F.Fab") hide
        (effects (font (size 0.7 0.7) (thickness 0.15)) (justify left bottom))
    )
    (fp_rect (start -0.925 -0.47) (end 0.925 0.47)
      (stroke (width 0.05) (type default)) (fill none) (layer "F.CrtYd"))
    (fp_rect (start -0.5 -0.25) (end 0.5 0.25)
      (stroke (width 0.15) (type solid)) (fill none) (layer "F.Fab"))
    (pad "1" smd roundrect (at -0.48 0 270) (size 0.59 0.64) (layers "F.Cu" "F.Paste" "F.Mask") (roundrect_rratio 0.25)
      (net 155 "RGMII_RXD1") (pintype "passive"))
    (pad "2" smd roundrect (at 0.48 0 270) (size 0.59 0.64) (layers "F.Cu" "F.Paste" "F.Mask") (roundrect_rratio 0.25)
      (net 2 "VCC3V3") (pintype "passive"))
  )
	(footprint "antmicro-footprints:R_0402_1005Metric" (layer "F.Cu")
    (at 104 104 -90)
    (descr "Resistor SMD 0402")
    (tags "resistor SMD 0402")
    (property "Author" "Antmicro")
    (property "License" "Apache-2.0")
    (property "MPN" "CR0402-FX-1022GLF")
    (property "Manufacturer" "Bourns")
    (property "Public" "False")
    (property "Sheetfile" "ethernet.kicad_sch")
    (property "Sheetname" "Ethernet")
    (property "Tolerance" "1%")
    (property "Val" "10k2")
    (property "ki_description" "SMD Chip Resistor")
    (property "ki_keywords" "0402, SMT, RESISTOR, PASSIVE")
    (attr smd)
    (fp_text reference "R1" (at 0.04 -8.946428 90) (layer "F.SilkS")
        (effects (font (size 0.7 0.7) (thickness 0.127)))
    )
    (fp_text value "R_10k2_0402" (at 0 1.17 90) (layer "F.Fab")
        (effects (font (size 1 1) (thickness 0.15)))
    )
    (fp_text user "Author: Antmicro" (at -0.95 4.169 -90) (layer "F.Fab") hide
        (effects (font (size 0.7 0.7) (thickness 0.15)) (justify left bottom))
    )
    (fp_text user "License: Apache-2.0" (at -0.95 5.169 -90) (layer "F.Fab") hide
        (effects (font (size 0.7 0.7) (thickness 0.15)) (justify left bottom))
    )
    (fp_text user "${REFERENCE}" (at 0 0 90) (layer "F.Fab")
        (effects (font (size 0.25 0.25) (thickness 0.04)))
    )
    (fp_rect (start -0.925 -0.47) (end 0.925 0.47)
      (stroke (width 0.05) (type default)) (fill none) (layer "F.CrtYd"))
    (fp_rect (start -0.5 -0.25) (end 0.5 0.25)
      (stroke (width 0.15) (type solid)) (fill none) (layer "F.Fab"))
    (pad "1" smd roundrect (at -0.48 0 270) (size 0.59 0.64) (layers "F.Cu" "F.Paste" "F.Mask") (roundrect_rratio 0.25)
      (net 154 "RGMII_RXD0") (pintype "passive"))
    (pad "2" smd roundrect (at 0.48 0 270) (size 0.59 0.64) (layers "F.Cu" "F.Paste" "F.Mask") (roundrect_rratio 0.25)
      (net 2 "VCC3V3") (pintype "passive"))
  )
	(footprint "antmicro-footprints:R_0402_1005Metric" (layer "F.Cu")
    (at 108.95 93.75 180)
    (descr "Resistor SMD 0402")
    (tags "resistor SMD 0402")
    (property "Author" "Antmicro")
    (property "License" "Apache-2.0")
    (property "MPN" "CR0402-FX-1212GLF")
    (property "Manufacturer" "Bourns")
    (property "Public" "False")
    (property "Sheetfile" "ethernet.kicad_sch")
    (property "Sheetname" "Ethernet")
    (property "Tolerance" "1%")
    (property "Val" "12k1")
    (property "ki_description" "SMD Chip Resistor, 12.1 kohm, ± 1%, 62.5 mW, 0402 [1005 Metric], Thick Film, General Purpose")
    (property "ki_keywords" "0402, SMT, RESISTOR, PASSIVE")
    (attr smd)
    (fp_text reference "R13" (at -0.01 1.1) (layer "F.SilkS")
        (effects (font (size 0.7 0.7) (thickness 0.127)))
    )
    (fp_text value "R_12k1_0402" (at 0 1.17) (layer "F.Fab")
        (effects (font (size 1 1) (thickness 0.15)))
    )
    (fp_text user "License: Apache-2.0" (at -0.95 5.169 180) (layer "F.Fab") hide
        (effects (font (size 0.7 0.7) (thickness 0.15)) (justify left bottom))
    )
    (fp_text user "${REFERENCE}" (at 0 0) (layer "F.Fab")
        (effects (font (size 0.25 0.25) (thickness 0.04)))
    )
    (fp_text user "Author: Antmicro" (at -0.95 4.169 180) (layer "F.Fab") hide
        (effects (font (size 0.7 0.7) (thickness 0.15)) (justify left bottom))
    )
    (fp_rect (start -0.925 -0.47) (end 0.925 0.47)
      (stroke (width 0.05) (type default)) (fill none) (layer "F.CrtYd"))
    (fp_rect (start -0.5 -0.25) (end 0.5 0.25)
      (stroke (width 0.15) (type solid)) (fill none) (layer "F.Fab"))
    (pad "1" smd roundrect (at -0.48 0 180) (size 0.59 0.64) (layers "F.Cu" "F.Paste" "F.Mask") (roundrect_rratio 0.25)
      (net 1 "GND") (pintype "passive"))
    (pad "2" smd roundrect (at 0.48 0 180) (size 0.59 0.64) (layers "F.Cu" "F.Paste" "F.Mask") (roundrect_rratio 0.25)
      (net 402 "Net-(U1-ISET)") (pintype "passive"))
  )
	(footprint "antmicro-footprints:R_0402_1005Metric" (layer "F.Cu")
    (at 108.95 96.15 180)
    (descr "Resistor SMD 0402")
    (tags "resistor SMD 0402")
    (property "Author" "Antmicro")
    (property "License" "Apache-2.0")
    (property "MPN" "CR0402-FX-4701GLF")
    (property "Manufacturer" "Bourns")
    (property "Public" "False")
    (property "Sheetfile" "ethernet.kicad_sch")
    (property "Sheetname" "Ethernet")
    (property "Tolerance" "1%")
    (property "Val" "4k7")
    (property "ki_description" "SMD Chip Resistor, 4.7 kohm, ± 1%, 62.5 mW, 0402 [1005 Metric], Thick Film, General Purpose")
    (property "ki_keywords" "0402, SMT, RESISTOR, PASSIVE")
    (attr smd)
    (fp_text reference "R48" (at -0.075 1.075) (layer "F.SilkS")
        (effects (font (size 0.7 0.7) (thickness 0.127)))
    )
    (fp_text value "R_4k7_0402" (at 0 1.17) (layer "F.Fab")
        (effects (font (size 1 1) (thickness 0.15)))
    )
    (fp_text user "${REFERENCE}" (at 0 0) (layer "F.Fab")
        (effects (font (size 0.25 0.25) (thickness 0.04)))
    )
    (fp_text user "Author: Antmicro" (at -0.95 4.169 180) (layer "F.Fab") hide
        (effects (font (size 0.7 0.7) (thickness 0.15)) (justify left bottom))
    )
    (fp_text user "License: Apache-2.0" (at -0.95 5.169 180) (layer "F.Fab") hide
        (effects (font (size 0.7 0.7) (thickness 0.15)) (justify left bottom))
    )
    (fp_rect (start -0.925 -0.47) (end 0.925 0.47)
      (stroke (width 0.05) (type default)) (fill none) (layer "F.CrtYd"))
    (fp_rect (start -0.5 -0.25) (end 0.5 0.25)
      (stroke (width 0.15) (type solid)) (fill none) (layer "F.Fab"))
    (pad "1" smd roundrect (at -0.48 0 180) (size 0.59 0.64) (layers "F.Cu" "F.Paste" "F.Mask") (roundrect_rratio 0.25)
      (net 2 "VCC3V3") (pintype "passive"))
    (pad "2" smd roundrect (at 0.48 0 180) (size 0.59 0.64) (layers "F.Cu" "F.Paste" "F.Mask") (roundrect_rratio 0.25)
      (net 163 "ETH_~{RESET}") (pintype "passive"))
  )
)
